# BASEBOARD_FAB2 (Tioga Pass) — schematic netlist excerpt (pin names and nets, part order shuffled) for the footprints in the layout excerpt that follows; sources: Cadence DE-HDL packaged netlist, KiCad conversion of Wiwynn_Tioga_Pass_MB.brd

C8E2  CAP_A  0.1UF 16V 10% X7R  pkg 0402V  page 170 : A = P3V3_STBY ; B = GND

U25W11  GTL2014  IC  pkg SM  page 255
  DIR  = PD_GTL2014_DIR_6
  B0  = PD_GTL2014_6_B0
  B1  = XDP_PRDY_N
  VREF  = P0V7_GTL2014_VREF_6
  B2  = PD_GTL2014_6_B2
  B3  = XDP_TDO
  GND(0)  = GND
  GND(1)  = GND
  A3  = JTAG_BMC_BUF_TDO_R
  A2  = TP_GTL2014_6_A2
  GND(2)  = GND
  A1  = BMC_PRDY_N
  A0  = TP_GTL2014_6_A0
  VCC  = P3V3_STBY

(kicad_pcb
	(version 20260206)
	(generator "pcbnew")
	(generator_version "10.0")
	(general
		(thickness 1.6)
		(legacy_teardrops no)
	)
	(paper "A4")
	(title_block
		(title "Wiwynn_Tioga_Pass_MB.brd")
		(comment 1 "Tioga Pass / footprints 706-707 of 4770")
	)
	(layers
		(0 "F.Cu" signal "TOP")
		(4 "In1.Cu" signal "L2GND")
		(6 "In2.Cu" signal "L3")
		(8 "In3.Cu" signal "L4GND")
		(10 "In4.Cu" signal "L5")
		(12 "In5.Cu" signal "L6GND")
		(14 "In6.Cu" signal "L7VCC")
		(16 "In7.Cu" signal "L8VCC")
		(18 "In8.Cu" signal "L9GND")
		(20 "In9.Cu" signal "L10")
		(22 "In10.Cu" signal "L11GND")
		(24 "In11.Cu" signal "L12")
		(26 "In12.Cu" signal "L13GND")
		(2 "B.Cu" signal "BOTTOM")
		(9 "F.Adhes" user "F.Adhesive")
		(11 "B.Adhes" user "B.Adhesive")
		(13 "F.Paste" user "Package Geometry/Pastemask Top")
		(15 "B.Paste" user "Package Geometry/Pastemask Bottom")
		(5 "F.SilkS" user "Ref Des/Silkscreen Top")
		(7 "B.SilkS" user "Ref Des/Silkscreen Bottom")
		(1 "F.Mask" user "Board Geometry/Soldermask Top")
		(3 "B.Mask" user "Board Geometry/Soldermask Bottom")
		(17 "Dwgs.User" user "User.Drawings")
		(19 "Cmts.User" user "User.Comments")
		(21 "Eco1.User" user "User.Eco1")
		(23 "Eco2.User" user "User.Eco2")
		(25 "Edge.Cuts" user "Board Geometry/Outline")
		(27 "Margin" user)
		(31 "F.CrtYd" user "Package Geometry/Place Bound Top")
		(29 "B.CrtYd" user "Package Geometry/Place Bound Bottom")
		(35 "F.Fab" user "Ref Des/Assembly Top")
		(33 "B.Fab" user "Ref Des/Assembly Bottom")
	)
	(footprint ""
		(layer "F.Cu")
		(at 418.6428 -86.4235)
		(property "Reference" "C8E2"
			(at 0 0 0)
			(layer "F.SilkS")
			(hide yes)
			(effects
				(font
					(size 1.27 1.27)
				)
			)
		)
		(property "Value" ""
			(at 0 0 0)
			(layer "F.Fab")
			(effects
				(font
					(size 1.27 1.27)
				)
			)
		)
		(duplicate_pad_numbers_are_jumpers no)
		(fp_poly
			(pts
				(xy 0.3048 -0.1016) (xy 0.3048 0.9906) (xy -0.3048 0.9906) (xy -0.3048 -0.1016)
			)
			(stroke
				(width 0)
				(type default)
			)
			(fill no)
			(layer "F.CrtYd")
		)
		(fp_line
			(start -0.3048 -0.1016)
			(end -0.3048 0.9906)
			(stroke
				(width 0.1)
				(type default)
			)
			(layer "F.Fab")
		)
		(fp_line
			(start -0.3048 0.9906)
			(end 0.3048 0.9906)
			(stroke
				(width 0.1)
				(type default)
			)
			(layer "F.Fab")
		)
		(fp_line
			(start 0.3048 -0.1016)
			(end -0.3048 -0.1016)
			(stroke
				(width 0.1)
				(type default)
			)
			(layer "F.Fab")
		)
		(fp_line
			(start 0.3048 0.9906)
			(end 0.3048 -0.1016)
			(stroke
				(width 0.1)
				(type default)
			)
			(layer "F.Fab")
		)
		(pad "1" smd rect
			(at 0 0)
			(size 0.508 0.508)
			(layers "F.Cu" "F.Mask" "F.Paste")
			(net "P3V3_STBY")
		)
		(pad "2" smd rect
			(at 0 0.889)
			(size 0.508 0.508)
			(layers "F.Cu" "F.Mask" "F.Paste")
			(net "GND")
		)
		(zone
			(layer "F.Cu")
			(hatch none 0.5)
			(connect_pads
				(clearance 0)
			)
			(min_thickness 0.25)
			(keepout
				(tracks allowed)
				(vias not_allowed)
				(pads allowed)
				(copperpour not_allowed)
				(footprints allowed)
			)
			(placement
				(enabled no)
				(sheetname "")
			)
			(fill
				(thermal_gap 0.5)
				(thermal_bridge_width 0.5)
				(island_removal_mode 0)
			)
			(polygon
				(pts
					(xy 418.3888 -86.1695) (xy 418.8968 -86.1695) (xy 418.8968 -85.7885) (xy 418.3888 -85.7885)
				)
			)
		)
		(zone
			(layer "F.Cu")
			(hatch none 0.5)
			(connect_pads
				(clearance 0)
			)
			(min_thickness 0.25)
			(keepout
				(tracks not_allowed)
				(vias allowed)
				(pads allowed)
				(copperpour not_allowed)
				(footprints allowed)
			)
			(placement
				(enabled no)
				(sheetname "")
			)
			(fill
				(thermal_gap 0.5)
				(thermal_bridge_width 0.5)
				(island_removal_mode 0)
			)
			(polygon
				(pts
					(xy 418.3888 -85.7885) (xy 418.8968 -85.7885) (xy 418.8968 -86.1695) (xy 418.3888 -86.1695)
				)
			)
		)
	)
	(footprint ""
		(layer "F.Cu")
		(at 450.1642 -147.7645 180)
		(property "Reference" "U25W11"
			(at 2.159 -1.57988 180)
			(unlocked yes)
			(layer "F.SilkS")
			(effects
				(font
					(size 0.4064 0.254)
					(thickness 0.1524)
				)
				(justify left)
			)
		)
		(property "Value" ""
			(at 0 0 180)
			(layer "F.Fab")
			(effects
				(font
					(size 1.27 1.27)
				)
			)
		)
		(duplicate_pad_numbers_are_jumpers no)
		(fp_line
			(start 4.4323 4.52628)
			(end 1.5367 4.52628)
			(stroke
				(width 0.1524)
				(type default)
			)
			(layer "F.SilkS")
		)
		(fp_line
			(start 4.4323 -0.64008)
			(end 4.4323 4.52628)
			(stroke
				(width 0.1524)
				(type default)
			)
			(layer "F.SilkS")
		)
		(fp_line
			(start 3.302 0.49022)
			(end 3.302 -0.64008)
			(stroke
				(width 0.1524)
				(type default)
			)
			(layer "F.SilkS")
		)
		(fp_line
			(start 2.667 0.49022)
			(end 3.302 0.49022)
			(stroke
				(width 0.1524)
				(type default)
			)
			(layer "F.SilkS")
		)
		(fp_line
			(start 2.667 -0.64008)
			(end 2.667 0.49022)
			(stroke
				(width 0.1524)
				(type default)
			)
			(layer "F.SilkS")
		)
		(fp_line
			(start 1.5367 4.52628)
			(end 1.5367 -0.64008)
			(stroke
				(width 0.1524)
				(type default)
			)
			(layer "F.SilkS")
		)
		(fp_line
			(start 1.5367 -0.64008)
			(end 4.4323 -0.64008)
			(stroke
				(width 0.1524)
				(type default)
			)
			(layer "F.SilkS")
		)
		(fp_circle
			(center -1.224788 -0.581152)
			(end -1.351788 -0.581152)
			(stroke
				(width 0.254)
				(type default)
			)
			(fill no)
			(layer "F.SilkS")
		)
		(fp_poly
			(pts
				(xy 0.7366 4.54152) (xy 0.7366 -0.64008) (xy 4.7244 -0.64008) (xy 5.2324 -0.64008) (xy 5.2324 4.54152)
				(xy 4.7244 4.54152)
			)
			(stroke
				(width 0)
				(type default)
			)
			(fill no)
			(layer "F.CrtYd")
		)
		(fp_line
			(start 5.2324 4.54152)
			(end 0.7366 4.54152)
			(stroke
				(width 0.1)
				(type default)
			)
			(layer "F.Fab")
		)
		(fp_line
			(start 5.2324 -0.64008)
			(end 5.2324 4.54152)
			(stroke
				(width 0.1)
				(type default)
			)
			(layer "F.Fab")
		)
		(fp_line
			(start 3.302 0.49022)
			(end 3.302 -0.64008)
			(stroke
				(width 0.1)
				(type default)
			)
			(layer "F.Fab")
		)
		(fp_line
			(start 2.667 0.49022)
			(end 3.302 0.49022)
			(stroke
				(width 0.1)
				(type default)
			)
			(layer "F.Fab")
		)
		(fp_line
			(start 2.667 -0.64008)
			(end 2.667 0.49022)
			(stroke
				(width 0.1)
				(type default)
			)
			(layer "F.Fab")
		)
		(fp_line
			(start 0.7366 4.54152)
			(end 0.7366 -0.64008)
			(stroke
				(width 0.1)
				(type default)
			)
			(layer "F.Fab")
		)
		(fp_line
			(start 0.7366 -0.64008)
			(end 5.2324 -0.64008)
			(stroke
				(width 0.1)
				(type default)
			)
			(layer "F.Fab")
		)
		(fp_circle
			(center -1.612138 -0.684784)
			(end -1.739138 -0.684784)
			(stroke
				(width 0.254)
				(type default)
			)
			(fill no)
			(layer "F.Fab")
		)
		(pad "1" smd rect
			(at 0 0 180)
			(size 2.159 0.381)
			(layers "F.Cu" "F.Mask" "F.Paste")
			(net "PD_GTL2014_DIR_6")
		)
		(pad "2" smd rect
			(at 0 0.65024 180)
			(size 2.159 0.381)
			(layers "F.Cu" "F.Mask" "F.Paste")
			(net "PD_GTL2014_6_B0")
		)
		(pad "3" smd rect
			(at 0 1.30048 180)
			(size 2.159 0.381)
			(layers "F.Cu" "F.Mask" "F.Paste")
			(net "XDP_PRDY_N")
		)
		(pad "4" smd rect
			(at 0 1.95072 180)
			(size 2.159 0.381)
			(layers "F.Cu" "F.Mask" "F.Paste")
			(net "P0V7_GTL2014_VREF_6")
		)
		(pad "5" smd rect
			(at 0 2.60096 180)
			(size 2.159 0.381)
			(layers "F.Cu" "F.Mask" "F.Paste")
			(net "PD_GTL2014_6_B2")
		)
		(pad "6" smd rect
			(at 0 3.2512 180)
			(size 2.159 0.381)
			(layers "F.Cu" "F.Mask" "F.Paste")
			(net "XDP_TDO")
		)
		(pad "7" smd rect
			(at 0 3.90144 180)
			(size 2.159 0.381)
			(layers "F.Cu" "F.Mask" "F.Paste")
			(net "GND")
		)
		(pad "8" smd rect
			(at 5.969 3.90144 180)
			(size 2.159 0.381)
			(layers "F.Cu" "F.Mask" "F.Paste")
			(net "GND")
		)
		(pad "9" smd rect
			(at 5.969 3.2512 180)
			(size 2.159 0.381)
			(layers "F.Cu" "F.Mask" "F.Paste")
			(net "JTAG_BMC_BUF_TDO_R")
		)
		(pad "10" smd rect
			(at 5.969 2.60096 180)
			(size 2.159 0.381)
			(layers "F.Cu" "F.Mask" "F.Paste")
			(net "TP_GTL2014_6_A2")
		)
		(pad "11" smd rect
			(at 5.969 1.95072 180)
			(size 2.159 0.381)
			(layers "F.Cu" "F.Mask" "F.Paste")
			(net "GND")
		)
		(pad "12" smd rect
			(at 5.969 1.30048 180)
			(size 2.159 0.381)
			(layers "F.Cu" "F.Mask" "F.Paste")
			(net "BMC_PRDY_N")
		)
		(pad "13" smd rect
			(at 5.969 0.65024 180)
			(size 2.159 0.381)
			(layers "F.Cu" "F.Mask" "F.Paste")
			(net "TP_GTL2014_6_A0")
		)
		(pad "14" smd rect
			(at 5.969 0 180)
			(size 2.159 0.381)
			(layers "F.Cu" "F.Mask" "F.Paste")
			(net "P3V3_STBY")
		)
	)
)
